# T6G (Grand Teton) — schematic netlist excerpt (pin names and nets, part order shuffled) for the footprints in the layout excerpt that follows; sources: Cadence DE-HDL packaged netlist, KiCad conversion of 04192023_DAF0TMB3IC0_F0TG_MB_C_brd_V02_OCP.brd

PC152_C0P0_6  Q_CAP  2.2UF 10V 10% X6S  pkg C0402  page 196 : A = PVDDCR_CPU0_P0_PVCC ; B = GND
PC550_3  Q_CAP  1UF 25V 10% X6S  pkg C0402  page 195 : A = SW_P12V_AUX_PVDDCR_CPU0_P0_FLT ; B = GND

(kicad_pcb
	(version 20260206)
	(generator "pcbnew")
	(generator_version "10.0")
	(general
		(thickness 1.6)
		(legacy_teardrops no)
	)
	(paper "A4")
	(title_block
		(title "04192023_DAF0TMB3IC0_F0TG_MB_C_brd_V02_OCP.brd")
		(comment 1 "Grand Teton / footprints 1380-1381 of 8354")
	)
	(layers
		(0 "F.Cu" signal "TOP")
		(4 "In1.Cu" signal "GND")
		(6 "In2.Cu" signal "IN1")
		(8 "In3.Cu" signal "GND1")
		(10 "In4.Cu" signal "IN2")
		(12 "In5.Cu" signal "GND2")
		(14 "In6.Cu" signal "IN3")
		(16 "In7.Cu" signal "GND3")
		(18 "In8.Cu" signal "VCC")
		(20 "In9.Cu" signal "VCC1")
		(22 "In10.Cu" signal "GND4")
		(24 "In11.Cu" signal "IN4")
		(26 "In12.Cu" signal "GND5")
		(28 "In13.Cu" signal "IN5")
		(30 "In14.Cu" signal "GND6")
		(32 "In15.Cu" signal "IN6")
		(34 "In16.Cu" signal "GND7")
		(2 "B.Cu" signal "BOTTOM")
		(9 "F.Adhes" user "F.Adhesive")
		(11 "B.Adhes" user "B.Adhesive")
		(13 "F.Paste" user "Package Geometry/Pastemask Top")
		(15 "B.Paste" user "Package Geometry/Pastemask Bottom")
		(5 "F.SilkS" user "Ref Des/Silkscreen Top")
		(7 "B.SilkS" user "Ref Des/Silkscreen Bottom")
		(1 "F.Mask" user "Board Geometry/Soldermask Top")
		(3 "B.Mask" user "Board Geometry/Soldermask Bottom")
		(17 "Dwgs.User" user "User.Drawings")
		(19 "Cmts.User" user "User.Comments")
		(21 "Eco1.User" user "User.Eco1")
		(23 "Eco2.User" user "User.Eco2")
		(25 "Edge.Cuts" user "Board Geometry/Outline")
		(27 "Margin" user)
		(31 "F.CrtYd" user "Package Geometry/Place Bound Top")
		(29 "B.CrtYd" user "Package Geometry/Place Bound Bottom")
		(35 "F.Fab" user "Ref Des/Assembly Top")
		(33 "B.Fab" user "Ref Des/Assembly Bottom")
	)
	(footprint ""
		(layer "F.Cu")
		(at 377.417838 -182.661052 90)
		(property "Reference" "PC550_3"
			(at 0 0 90)
			(layer "F.SilkS")
			(hide yes)
			(effects
				(font
					(size 1.27 1.27)
				)
			)
		)
		(property "Value" ""
			(at 0 0 90)
			(layer "F.Fab")
			(effects
				(font
					(size 1.27 1.27)
				)
			)
		)
		(duplicate_pad_numbers_are_jumpers no)
		(fp_line
			(start 0.7874 -0.4064)
			(end 0.7874 0.4064)
			(stroke
				(width 0.1524)
				(type default)
			)
			(layer "F.SilkS")
		)
		(fp_line
			(start -0.7874 -0.4064)
			(end 0.7874 -0.4064)
			(stroke
				(width 0.1524)
				(type default)
			)
			(layer "F.SilkS")
		)
		(fp_line
			(start 0.7874 0.4064)
			(end -0.7874 0.4064)
			(stroke
				(width 0.1524)
				(type default)
			)
			(layer "F.SilkS")
		)
		(fp_line
			(start -0.7874 0.4064)
			(end -0.7874 -0.4064)
			(stroke
				(width 0.1524)
				(type default)
			)
			(layer "F.SilkS")
		)
		(fp_line
			(start -0.12065 -0.305054)
			(end -0.12065 -0.2794)
			(stroke
				(width 0.1)
				(type default)
			)
			(layer "F.Fab")
		)
		(fp_line
			(start -0.67945 -0.305054)
			(end -0.12065 -0.305054)
			(stroke
				(width 0.1)
				(type default)
			)
			(layer "F.Fab")
		)
		(fp_line
			(start 0.67945 -0.3048)
			(end 0.67945 0.3048)
			(stroke
				(width 0.1)
				(type default)
			)
			(layer "F.Fab")
		)
		(fp_line
			(start 0.12065 -0.3048)
			(end 0.67945 -0.3048)
			(stroke
				(width 0.1)
				(type default)
			)
			(layer "F.Fab")
		)
		(fp_line
			(start 0.12065 -0.2794)
			(end 0.12065 -0.3048)
			(stroke
				(width 0.1)
				(type default)
			)
			(layer "F.Fab")
		)
		(fp_line
			(start -0.12065 -0.2794)
			(end 0.12065 -0.2794)
			(stroke
				(width 0.1)
				(type default)
			)
			(layer "F.Fab")
		)
		(fp_line
			(start 0.120396 0.2794)
			(end -0.12065 0.2794)
			(stroke
				(width 0.1)
				(type default)
			)
			(layer "F.Fab")
		)
		(fp_line
			(start -0.12065 0.2794)
			(end -0.12065 0.3048)
			(stroke
				(width 0.1)
				(type default)
			)
			(layer "F.Fab")
		)
		(fp_line
			(start 0.67945 0.3048)
			(end 0.120396 0.3048)
			(stroke
				(width 0.1)
				(type default)
			)
			(layer "F.Fab")
		)
		(fp_line
			(start 0.120396 0.3048)
			(end 0.120396 0.2794)
			(stroke
				(width 0.1)
				(type default)
			)
			(layer "F.Fab")
		)
		(fp_line
			(start -0.12065 0.3048)
			(end -0.67945 0.3048)
			(stroke
				(width 0.1)
				(type default)
			)
			(layer "F.Fab")
		)
		(fp_line
			(start -0.67945 0.3048)
			(end -0.67945 -0.305054)
			(stroke
				(width 0.1)
				(type default)
			)
			(layer "F.Fab")
		)
		(pad "1" smd circle
			(at -0.40005 0 90)
			(size 0 0)
			(layers "F.Cu" "F.Mask" "F.Paste")
			(net "SW_P12V_AUX_PVDDCR_CPU0_P0_FLT")
		)
		(pad "2" smd circle
			(at 0.40005 0 90)
			(size 0 0)
			(layers "F.Cu" "F.Mask" "F.Paste")
			(net "GND")
		)
	)
	(footprint ""
		(layer "F.Cu")
		(at 351.410778 -161.141156 90)
		(property "Reference" "PC152_C0P0_6"
			(at 0 0 90)
			(layer "F.SilkS")
			(hide yes)
			(effects
				(font
					(size 1.27 1.27)
				)
			)
		)
		(property "Value" ""
			(at 0 0 90)
			(layer "F.Fab")
			(effects
				(font
					(size 1.27 1.27)
				)
			)
		)
		(duplicate_pad_numbers_are_jumpers no)
		(fp_line
			(start 0.7874 -0.4064)
			(end 0.7874 0.4064)
			(stroke
				(width 0.1524)
				(type default)
			)
			(layer "F.SilkS")
		)
		(fp_line
			(start -0.7874 -0.4064)
			(end 0.7874 -0.4064)
			(stroke
				(width 0.1524)
				(type default)
			)
			(layer "F.SilkS")
		)
		(fp_line
			(start 0.7874 0.4064)
			(end -0.7874 0.4064)
			(stroke
				(width 0.1524)
				(type default)
			)
			(layer "F.SilkS")
		)
		(fp_line
			(start -0.7874 0.4064)
			(end -0.7874 -0.4064)
			(stroke
				(width 0.1524)
				(type default)
			)
			(layer "F.SilkS")
		)
		(fp_line
			(start -0.12065 -0.305054)
			(end -0.12065 -0.2794)
			(stroke
				(width 0.1)
				(type default)
			)
			(layer "F.Fab")
		)
		(fp_line
			(start -0.67945 -0.305054)
			(end -0.12065 -0.305054)
			(stroke
				(width 0.1)
				(type default)
			)
			(layer "F.Fab")
		)
		(fp_line
			(start 0.67945 -0.3048)
			(end 0.67945 0.3048)
			(stroke
				(width 0.1)
				(type default)
			)
			(layer "F.Fab")
		)
		(fp_line
			(start 0.12065 -0.3048)
			(end 0.67945 -0.3048)
			(stroke
				(width 0.1)
				(type default)
			)
			(layer "F.Fab")
		)
		(fp_line
			(start 0.12065 -0.2794)
			(end 0.12065 -0.3048)
			(stroke
				(width 0.1)
				(type default)
			)
			(layer "F.Fab")
		)
		(fp_line
			(start -0.12065 -0.2794)
			(end 0.12065 -0.2794)
			(stroke
				(width 0.1)
				(type default)
			)
			(layer "F.Fab")
		)
		(fp_line
			(start 0.120396 0.2794)
			(end -0.12065 0.2794)
			(stroke
				(width 0.1)
				(type default)
			)
			(layer "F.Fab")
		)
		(fp_line
			(start -0.12065 0.2794)
			(end -0.12065 0.3048)
			(stroke
				(width 0.1)
				(type default)
			)
			(layer "F.Fab")
		)
		(fp_line
			(start 0.67945 0.3048)
			(end 0.120396 0.3048)
			(stroke
				(width 0.1)
				(type default)
			)
			(layer "F.Fab")
		)
		(fp_line
			(start 0.120396 0.3048)
			(end 0.120396 0.2794)
			(stroke
				(width 0.1)
				(type default)
			)
			(layer "F.Fab")
		)
		(fp_line
			(start -0.12065 0.3048)
			(end -0.67945 0.3048)
			(stroke
				(width 0.1)
				(type default)
			)
			(layer "F.Fab")
		)
		(fp_line
			(start -0.67945 0.3048)
			(end -0.67945 -0.305054)
			(stroke
				(width 0.1)
				(type default)
			)
			(layer "F.Fab")
		)
		(pad "1" smd circle
			(at -0.40005 0 90)
			(size 0 0)
			(layers "F.Cu" "F.Mask" "F.Paste")
			(net "PVDDCR_CPU0_P0_PVCC")
		)
		(pad "2" smd circle
			(at 0.40005 0 90)
			(size 0 0)
			(layers "F.Cu" "F.Mask" "F.Paste")
			(net "GND")
		)
	)
)
